(kicad_pcb
	(version 20260206)
	(generator "pcbnew")
	(generator_version "10.0")
	(general
		(thickness 1.6)
		(legacy_teardrops no)
	)
	(paper "A4")
	(title_block
		(title "04192023_DAF0TMB3IC0_F0TG_MB_C_brd_V02_OCP.brd")
		(comment 1 "Grand Teton / footprints 2062-2068 of 8354")
	)
	(layers
		(0 "F.Cu" signal "TOP")
		(4 "In1.Cu" signal "GND")
		(6 "In2.Cu" signal "IN1")
		(8 "In3.Cu" signal "GND1")
		(10 "In4.Cu" signal "IN2")
		(12 "In5.Cu" signal "GND2")
		(14 "In6.Cu" signal "IN3")
		(16 "In7.Cu" signal "GND3")
		(18 "In8.Cu" signal "VCC")
		(20 "In9.Cu" signal "VCC1")
		(22 "In10.Cu" signal "GND4")
		(24 "In11.Cu" signal "IN4")
		(26 "In12.Cu" signal "GND5")
		(28 "In13.Cu" signal "IN5")
		(30 "In14.Cu" signal "GND6")
		(32 "In15.Cu" signal "IN6")
		(34 "In16.Cu" signal "GND7")
		(2 "B.Cu" signal "BOTTOM")
		(9 "F.Adhes" user "F.Adhesive")
		(11 "B.Adhes" user "B.Adhesive")
		(13 "F.Paste" user "Package Geometry/Pastemask Top")
		(15 "B.Paste" user "Package Geometry/Pastemask Bottom")
		(5 "F.SilkS" user "Ref Des/Silkscreen Top")
		(7 "B.SilkS" user "Ref Des/Silkscreen Bottom")
		(1 "F.Mask" user "Board Geometry/Soldermask Top")
		(3 "B.Mask" user "Board Geometry/Soldermask Bottom")
		(17 "Dwgs.User" user "User.Drawings")
		(19 "Cmts.User" user "User.Comments")
		(21 "Eco1.User" user "User.Eco1")
		(23 "Eco2.User" user "User.Eco2")
		(25 "Edge.Cuts" user "Board Geometry/Outline")
		(27 "Margin" user)
		(31 "F.CrtYd" user "Package Geometry/Place Bound Top")
		(29 "B.CrtYd" user "Package Geometry/Place Bound Bottom")
		(35 "F.Fab" user "Ref Des/Assembly Top")
		(33 "B.Fab" user "Ref Des/Assembly Bottom")
	)
	(footprint ""
		(layer "F.Cu")
		(at 103.185722 -26.435304 90)
		(property "Reference" "R6330"
			(at 0 0 90)
			(layer "F.SilkS")
			(hide yes)
			(effects
				(font
					(size 1.27 1.27)
				)
			)
		)
		(property "Value" ""
			(at 0 0 90)
			(layer "F.Fab")
			(effects
				(font
					(size 1.27 1.27)
				)
			)
		)
		(duplicate_pad_numbers_are_jumpers no)
		(fp_line
			(start 0.7874 -0.4064)
			(end 0.7874 0.4064)
			(stroke
				(width 0.1524)
				(type default)
			)
			(layer "F.SilkS")
		)
		(fp_line
			(start -0.7874 -0.4064)
			(end 0.7874 -0.4064)
			(stroke
				(width 0.1524)
				(type default)
			)
			(layer "F.SilkS")
		)
		(fp_line
			(start 0.7874 0.4064)
			(end -0.7874 0.4064)
			(stroke
				(width 0.1524)
				(type default)
			)
			(layer "F.SilkS")
		)
		(fp_line
			(start -0.7874 0.4064)
			(end -0.7874 -0.4064)
			(stroke
				(width 0.1524)
				(type default)
			)
			(layer "F.SilkS")
		)
		(fp_line
			(start -0.12065 -0.305054)
			(end -0.12065 -0.2794)
			(stroke
				(width 0.1)
				(type default)
			)
			(layer "F.Fab")
		)
		(fp_line
			(start -0.67945 -0.305054)
			(end -0.12065 -0.305054)
			(stroke
				(width 0.1)
				(type default)
			)
			(layer "F.Fab")
		)
		(fp_line
			(start 0.67945 -0.3048)
			(end 0.67945 0.3048)
			(stroke
				(width 0.1)
				(type default)
			)
			(layer "F.Fab")
		)
		(fp_line
			(start 0.12065 -0.3048)
			(end 0.67945 -0.3048)
			(stroke
				(width 0.1)
				(type default)
			)
			(layer "F.Fab")
		)
		(fp_line
			(start 0.12065 -0.2794)
			(end 0.12065 -0.3048)
			(stroke
				(width 0.1)
				(type default)
			)
			(layer "F.Fab")
		)
		(fp_line
			(start -0.12065 -0.2794)
			(end 0.12065 -0.2794)
			(stroke
				(width 0.1)
				(type default)
			)
			(layer "F.Fab")
		)
		(fp_line
			(start 0.120396 0.2794)
			(end -0.12065 0.2794)
			(stroke
				(width 0.1)
				(type default)
			)
			(layer "F.Fab")
		)
		(fp_line
			(start -0.12065 0.2794)
			(end -0.12065 0.3048)
			(stroke
				(width 0.1)
				(type default)
			)
			(layer "F.Fab")
		)
		(fp_line
			(start 0.67945 0.3048)
			(end 0.120396 0.3048)
			(stroke
				(width 0.1)
				(type default)
			)
			(layer "F.Fab")
		)
		(fp_line
			(start 0.120396 0.3048)
			(end 0.120396 0.2794)
			(stroke
				(width 0.1)
				(type default)
			)
			(layer "F.Fab")
		)
		(fp_line
			(start -0.12065 0.3048)
			(end -0.67945 0.3048)
			(stroke
				(width 0.1)
				(type default)
			)
			(layer "F.Fab")
		)
		(fp_line
			(start -0.67945 0.3048)
			(end -0.67945 -0.305054)
			(stroke
				(width 0.1)
				(type default)
			)
			(layer "F.Fab")
		)
		(pad "1" smd circle
			(at -0.40005 0 90)
			(size 0 0)
			(layers "F.Cu" "F.Mask" "F.Paste")
			(net "GND")
		)
		(pad "2" smd circle
			(at 0.40005 0 90)
			(size 0 0)
			(layers "F.Cu" "F.Mask" "F.Paste")
			(net "USB_HUB2_TI_NC_MRP_ATEST")
		)
	)
	(footprint ""
		(layer "F.Cu")
		(at 356.29596 -259.845048)
		(property "Reference" "C3898"
			(at 0 0 0)
			(layer "F.SilkS")
			(hide yes)
			(effects
				(font
					(size 1.27 1.27)
				)
			)
		)
		(property "Value" ""
			(at 0 0 0)
			(layer "F.Fab")
			(effects
				(font
					(size 1.27 1.27)
				)
			)
		)
		(duplicate_pad_numbers_are_jumpers no)
		(fp_line
			(start -0.7874 -0.4064)
			(end 0.7874 -0.4064)
			(stroke
				(width 0.1524)
				(type default)
			)
			(layer "F.SilkS")
		)
		(fp_line
			(start -0.7874 0.4064)
			(end -0.7874 -0.4064)
			(stroke
				(width 0.1524)
				(type default)
			)
			(layer "F.SilkS")
		)
		(fp_line
			(start 0.7874 -0.4064)
			(end 0.7874 0.4064)
			(stroke
				(width 0.1524)
				(type default)
			)
			(layer "F.SilkS")
		)
		(fp_line
			(start 0.7874 0.4064)
			(end -0.7874 0.4064)
			(stroke
				(width 0.1524)
				(type default)
			)
			(layer "F.SilkS")
		)
		(fp_line
			(start -0.67945 -0.305054)
			(end -0.12065 -0.305054)
			(stroke
				(width 0.1)
				(type default)
			)
			(layer "F.Fab")
		)
		(fp_line
			(start -0.67945 0.3048)
			(end -0.67945 -0.305054)
			(stroke
				(width 0.1)
				(type default)
			)
			(layer "F.Fab")
		)
		(fp_line
			(start -0.12065 -0.305054)
			(end -0.12065 -0.2794)
			(stroke
				(width 0.1)
				(type default)
			)
			(layer "F.Fab")
		)
		(fp_line
			(start -0.12065 -0.2794)
			(end 0.12065 -0.2794)
			(stroke
				(width 0.1)
				(type default)
			)
			(layer "F.Fab")
		)
		(fp_line
			(start -0.12065 0.2794)
			(end -0.12065 0.3048)
			(stroke
				(width 0.1)
				(type default)
			)
			(layer "F.Fab")
		)
		(fp_line
			(start -0.12065 0.3048)
			(end -0.67945 0.3048)
			(stroke
				(width 0.1)
				(type default)
			)
			(layer "F.Fab")
		)
		(fp_line
			(start 0.120396 0.2794)
			(end -0.12065 0.2794)
			(stroke
				(width 0.1)
				(type default)
			)
			(layer "F.Fab")
		)
		(fp_line
			(start 0.120396 0.3048)
			(end 0.120396 0.2794)
			(stroke
				(width 0.1)
				(type default)
			)
			(layer "F.Fab")
		)
		(fp_line
			(start 0.12065 -0.3048)
			(end 0.67945 -0.3048)
			(stroke
				(width 0.1)
				(type default)
			)
			(layer "F.Fab")
		)
		(fp_line
			(start 0.12065 -0.2794)
			(end 0.12065 -0.3048)
			(stroke
				(width 0.1)
				(type default)
			)
			(layer "F.Fab")
		)
		(fp_line
			(start 0.67945 -0.3048)
			(end 0.67945 0.3048)
			(stroke
				(width 0.1)
				(type default)
			)
			(layer "F.Fab")
		)
		(fp_line
			(start 0.67945 0.3048)
			(end 0.120396 0.3048)
			(stroke
				(width 0.1)
				(type default)
			)
			(layer "F.Fab")
		)
		(pad "1" smd circle
			(at -0.40005 0)
			(size 0 0)
			(layers "F.Cu" "F.Mask" "F.Paste")
			(net "PVDDIO_P0")
		)
		(pad "2" smd circle
			(at 0.40005 0)
			(size 0 0)
			(layers "F.Cu" "F.Mask" "F.Paste")
			(net "GND")
		)
	)
	(footprint ""
		(layer "F.Cu")
		(at 182.047134 -160.595818 90)
		(property "Reference" "R5020"
			(at 0 0 90)
			(layer "F.SilkS")
			(hide yes)
			(effects
				(font
					(size 1.27 1.27)
				)
			)
		)
		(property "Value" ""
			(at 0 0 90)
			(layer "F.Fab")
			(effects
				(font
					(size 1.27 1.27)
				)
			)
		)
		(duplicate_pad_numbers_are_jumpers no)
		(fp_line
			(start 0.7874 -0.4064)
			(end 0.7874 0.4064)
			(stroke
				(width 0.1524)
				(type default)
			)
			(layer "F.SilkS")
		)
		(fp_line
			(start -0.7874 -0.4064)
			(end 0.7874 -0.4064)
			(stroke
				(width 0.1524)
				(type default)
			)
			(layer "F.SilkS")
		)
		(fp_line
			(start 0.7874 0.4064)
			(end -0.7874 0.4064)
			(stroke
				(width 0.1524)
				(type default)
			)
			(layer "F.SilkS")
		)
		(fp_line
			(start -0.7874 0.4064)
			(end -0.7874 -0.4064)
			(stroke
				(width 0.1524)
				(type default)
			)
			(layer "F.SilkS")
		)
		(fp_line
			(start -0.12065 -0.305054)
			(end -0.12065 -0.2794)
			(stroke
				(width 0.1)
				(type default)
			)
			(layer "F.Fab")
		)
		(fp_line
			(start -0.67945 -0.305054)
			(end -0.12065 -0.305054)
			(stroke
				(width 0.1)
				(type default)
			)
			(layer "F.Fab")
		)
		(fp_line
			(start 0.67945 -0.3048)
			(end 0.67945 0.3048)
			(stroke
				(width 0.1)
				(type default)
			)
			(layer "F.Fab")
		)
		(fp_line
			(start 0.12065 -0.3048)
			(end 0.67945 -0.3048)
			(stroke
				(width 0.1)
				(type default)
			)
			(layer "F.Fab")
		)
		(fp_line
			(start 0.12065 -0.2794)
			(end 0.12065 -0.3048)
			(stroke
				(width 0.1)
				(type default)
			)
			(layer "F.Fab")
		)
		(fp_line
			(start -0.12065 -0.2794)
			(end 0.12065 -0.2794)
			(stroke
				(width 0.1)
				(type default)
			)
			(layer "F.Fab")
		)
		(fp_line
			(start 0.120396 0.2794)
			(end -0.12065 0.2794)
			(stroke
				(width 0.1)
				(type default)
			)
			(layer "F.Fab")
		)
		(fp_line
			(start -0.12065 0.2794)
			(end -0.12065 0.3048)
			(stroke
				(width 0.1)
				(type default)
			)
			(layer "F.Fab")
		)
		(fp_line
			(start 0.67945 0.3048)
			(end 0.120396 0.3048)
			(stroke
				(width 0.1)
				(type default)
			)
			(layer "F.Fab")
		)
		(fp_line
			(start 0.120396 0.3048)
			(end 0.120396 0.2794)
			(stroke
				(width 0.1)
				(type default)
			)
			(layer "F.Fab")
		)
		(fp_line
			(start -0.12065 0.3048)
			(end -0.67945 0.3048)
			(stroke
				(width 0.1)
				(type default)
			)
			(layer "F.Fab")
		)
		(fp_line
			(start -0.67945 0.3048)
			(end -0.67945 -0.305054)
			(stroke
				(width 0.1)
				(type default)
			)
			(layer "F.Fab")
		)
		(pad "1" smd circle
			(at -0.40005 0 90)
			(size 0 0)
			(layers "F.Cu" "F.Mask" "F.Paste")
			(net "PVDD11_S3_P1")
		)
		(pad "2" smd circle
			(at 0.40005 0 90)
			(size 0 0)
			(layers "F.Cu" "F.Mask" "F.Paste")
			(net "I3C_SCM_3_R_SCL")
		)
	)
	(footprint ""
		(layer "F.Cu")
		(at 170.299634 -423.870882 -90)
		(property "Reference" "U21"
			(at -0.392938 -3.18262 90)
			(unlocked yes)
			(layer "F.SilkS")
			(effects
				(font
					(size 0.7874 0.5842)
					(thickness 0.1524)
				)
				(justify left)
			)
		)
		(property "Value" ""
			(at 0 0 270)
			(layer "F.Fab")
			(effects
				(font
					(size 1.27 1.27)
				)
			)
		)
		(duplicate_pad_numbers_are_jumpers no)
		(fp_line
			(start -1.8288 2.500122)
			(end 1.8288 2.500122)
			(stroke
				(width 0.1524)
				(type default)
			)
			(layer "F.SilkS")
		)
		(fp_line
			(start 1.8288 2.500122)
			(end 1.8288 -2.500122)
			(stroke
				(width 0.1524)
				(type default)
			)
			(layer "F.SilkS")
		)
		(fp_line
			(start 0 -1.4224)
			(end -1.077722 -2.500122)
			(stroke
				(width 0.1524)
				(type default)
			)
			(layer "F.SilkS")
		)
		(fp_line
			(start -1.8288 -2.500122)
			(end -1.8288 2.500122)
			(stroke
				(width 0.1524)
				(type default)
			)
			(layer "F.SilkS")
		)
		(fp_line
			(start -1.077722 -2.500122)
			(end -1.8288 -2.500122)
			(stroke
				(width 0.1524)
				(type default)
			)
			(layer "F.SilkS")
		)
		(fp_line
			(start 1.077722 -2.500122)
			(end 0 -1.4224)
			(stroke
				(width 0.1524)
				(type default)
			)
			(layer "F.SilkS")
		)
		(fp_line
			(start 1.8288 -2.500122)
			(end 1.077722 -2.500122)
			(stroke
				(width 0.1524)
				(type default)
			)
			(layer "F.SilkS")
		)
		(fp_poly
			(pts
				(xy -4.51485 -2.535174) (xy -4.51485 -1.519174) (xy -3.49885 -2.027174)
			)
			(stroke
				(width 0)
				(type default)
			)
			(fill yes)
			(layer "F.SilkS")
		)
		(fp_line
			(start -1.999996 2.500122)
			(end 1.999996 2.500122)
			(stroke
				(width 0.1)
				(type default)
			)
			(layer "F.Fab")
		)
		(fp_line
			(start 1.999996 2.500122)
			(end 1.999996 -2.500122)
			(stroke
				(width 0.1)
				(type default)
			)
			(layer "F.Fab")
		)
		(fp_line
			(start -1.999996 -2.500122)
			(end -1.999996 2.500122)
			(stroke
				(width 0.1)
				(type default)
			)
			(layer "F.Fab")
		)
		(fp_line
			(start 1.999996 -2.500122)
			(end -1.999996 -2.500122)
			(stroke
				(width 0.1)
				(type default)
			)
			(layer "F.Fab")
		)
		(fp_poly
			(pts
				(xy -4.5085 -2.413) (xy -4.5085 -1.397) (xy -3.4925 -1.905)
			)
			(stroke
				(width 0)
				(type default)
			)
			(fill yes)
			(layer "F.Fab")
		)
		(pad "1" smd rect
			(at -2.599944 -1.905 180)
			(size 0.889 1.27)
			(layers "F.Cu" "F.Mask" "F.Paste")
			(net "Net_10833")
		)
		(pad "2" smd rect
			(at -2.599944 -0.635 180)
			(size 0.889 1.27)
			(layers "F.Cu" "F.Mask" "F.Paste")
			(net "Net_10832")
		)
		(pad "3" smd rect
			(at -2.599944 0.635 180)
			(size 0.889 1.27)
			(layers "F.Cu" "F.Mask" "F.Paste")
			(net "U21_E2")
		)
		(pad "4" smd rect
			(at -2.599944 1.905 180)
			(size 0.889 1.27)
			(layers "F.Cu" "F.Mask" "F.Paste")
			(net "GND")
		)
		(pad "5" smd rect
			(at 2.599944 1.905 180)
			(size 0.889 1.27)
			(layers "F.Cu" "F.Mask" "F.Paste")
			(net "SMB_RT_CPU1_P3_ROM_SDA")
		)
		(pad "6" smd rect
			(at 2.599944 0.635 180)
			(size 0.889 1.27)
			(layers "F.Cu" "F.Mask" "F.Paste")
			(net "SMB_RT_CPU1_P3_ROM_SCL")
		)
		(pad "7" smd rect
			(at 2.599944 -0.635 180)
			(size 0.889 1.27)
			(layers "F.Cu" "F.Mask" "F.Paste")
			(net "GND")
		)
		(pad "8" smd rect
			(at 2.599944 -1.905 180)
			(size 0.889 1.27)
			(layers "F.Cu" "F.Mask" "F.Paste")
			(net "P1V8_CPU1_RT_1D")
		)
	)
	(footprint ""
		(layer "F.Cu")
		(at 293.550086 -435.600094)
		(property "Reference" "H104"
			(at -7.357364 -3.906266 0)
			(unlocked yes)
			(layer "F.SilkS")
			(effects
				(font
					(size 0.7874 0.5842)
					(thickness 0.1524)
				)
				(justify left)
			)
		)
		(property "Value" ""
			(at 0 0 0)
			(layer "F.Fab")
			(effects
				(font
					(size 1.27 1.27)
				)
			)
		)
		(duplicate_pad_numbers_are_jumpers no)
		(pad "1" thru_hole circle
			(at 0 0)
			(size 10.0076 10.0076)
			(drill 5.6134)
			(layers "*.Cu" "*.Mask")
			(remove_unused_layers no)
			(net "GND")
			(clearance -1.9431)
		)
	)
	(footprint ""
		(layer "F.Cu")
		(at 214.613744 -23.304754 90)
		(property "Reference" "R1138"
			(at 0 0 90)
			(layer "F.SilkS")
			(hide yes)
			(effects
				(font
					(size 1.27 1.27)
				)
			)
		)
		(property "Value" ""
			(at 0 0 90)
			(layer "F.Fab")
			(effects
				(font
					(size 1.27 1.27)
				)
			)
		)
		(duplicate_pad_numbers_are_jumpers no)
		(fp_line
			(start 0.7874 -0.4064)
			(end 0.7874 0.4064)
			(stroke
				(width 0.1524)
				(type default)
			)
			(layer "F.SilkS")
		)
		(fp_line
			(start -0.7874 -0.4064)
			(end 0.7874 -0.4064)
			(stroke
				(width 0.1524)
				(type default)
			)
			(layer "F.SilkS")
		)
		(fp_line
			(start 0.7874 0.4064)
			(end -0.7874 0.4064)
			(stroke
				(width 0.1524)
				(type default)
			)
			(layer "F.SilkS")
		)
		(fp_line
			(start -0.7874 0.4064)
			(end -0.7874 -0.4064)
			(stroke
				(width 0.1524)
				(type default)
			)
			(layer "F.SilkS")
		)
		(fp_line
			(start -0.12065 -0.305054)
			(end -0.12065 -0.2794)
			(stroke
				(width 0.1)
				(type default)
			)
			(layer "F.Fab")
		)
		(fp_line
			(start -0.67945 -0.305054)
			(end -0.12065 -0.305054)
			(stroke
				(width 0.1)
				(type default)
			)
			(layer "F.Fab")
		)
		(fp_line
			(start 0.67945 -0.3048)
			(end 0.67945 0.3048)
			(stroke
				(width 0.1)
				(type default)
			)
			(layer "F.Fab")
		)
		(fp_line
			(start 0.12065 -0.3048)
			(end 0.67945 -0.3048)
			(stroke
				(width 0.1)
				(type default)
			)
			(layer "F.Fab")
		)
		(fp_line
			(start 0.12065 -0.2794)
			(end 0.12065 -0.3048)
			(stroke
				(width 0.1)
				(type default)
			)
			(layer "F.Fab")
		)
		(fp_line
			(start -0.12065 -0.2794)
			(end 0.12065 -0.2794)
			(stroke
				(width 0.1)
				(type default)
			)
			(layer "F.Fab")
		)
		(fp_line
			(start 0.120396 0.2794)
			(end -0.12065 0.2794)
			(stroke
				(width 0.1)
				(type default)
			)
			(layer "F.Fab")
		)
		(fp_line
			(start -0.12065 0.2794)
			(end -0.12065 0.3048)
			(stroke
				(width 0.1)
				(type default)
			)
			(layer "F.Fab")
		)
		(fp_line
			(start 0.67945 0.3048)
			(end 0.120396 0.3048)
			(stroke
				(width 0.1)
				(type default)
			)
			(layer "F.Fab")
		)
		(fp_line
			(start 0.120396 0.3048)
			(end 0.120396 0.2794)
			(stroke
				(width 0.1)
				(type default)
			)
			(layer "F.Fab")
		)
		(fp_line
			(start -0.12065 0.3048)
			(end -0.67945 0.3048)
			(stroke
				(width 0.1)
				(type default)
			)
			(layer "F.Fab")
		)
		(fp_line
			(start -0.67945 0.3048)
			(end -0.67945 -0.305054)
			(stroke
				(width 0.1)
				(type default)
			)
			(layer "F.Fab")
		)
		(pad "1" smd circle
			(at -0.40005 0 90)
			(size 0 0)
			(layers "F.Cu" "F.Mask" "F.Paste")
			(net "P3V3_AUX")
		)
		(pad "2" smd circle
			(at 0.40005 0 90)
			(size 0 0)
			(layers "F.Cu" "F.Mask" "F.Paste")
			(net "CLK_50M_EN")
		)
	)
	(footprint ""
		(layer "F.Cu")
		(at 241.112802 -70.143624 -90)
		(property "Reference" "R955"
			(at 0 0 270)
			(layer "F.SilkS")
			(hide yes)
			(effects
				(font
					(size 1.27 1.27)
				)
			)
		)
		(property "Value" ""
			(at 0 0 270)
			(layer "F.Fab")
			(effects
				(font
					(size 1.27 1.27)
				)
			)
		)
		(duplicate_pad_numbers_are_jumpers no)
		(fp_line
			(start -0.7874 0.4064)
			(end -0.7874 -0.4064)
			(stroke
				(width 0.1524)
				(type default)
			)
			(layer "F.SilkS")
		)
		(fp_line
			(start 0.7874 0.4064)
			(end -0.7874 0.4064)
			(stroke
				(width 0.1524)
				(type default)
			)
			(layer "F.SilkS")
		)
		(fp_line
			(start -0.7874 -0.4064)
			(end 0.7874 -0.4064)
			(stroke
				(width 0.1524)
				(type default)
			)
			(layer "F.SilkS")
		)
		(fp_line
			(start 0.7874 -0.4064)
			(end 0.7874 0.4064)
			(stroke
				(width 0.1524)
				(type default)
			)
			(layer "F.SilkS")
		)
		(fp_line
			(start -0.67945 0.3048)
			(end -0.67945 -0.305054)
			(stroke
				(width 0.1)
				(type default)
			)
			(layer "F.Fab")
		)
		(fp_line
			(start -0.12065 0.3048)
			(end -0.67945 0.3048)
			(stroke
				(width 0.1)
				(type default)
			)
			(layer "F.Fab")
		)
		(fp_line
			(start 0.120396 0.3048)
			(end 0.120396 0.2794)
			(stroke
				(width 0.1)
				(type default)
			)
			(layer "F.Fab")
		)
		(fp_line
			(start 0.67945 0.3048)
			(end 0.120396 0.3048)
			(stroke
				(width 0.1)
				(type default)
			)
			(layer "F.Fab")
		)
		(fp_line
			(start -0.12065 0.2794)
			(end -0.12065 0.3048)
			(stroke
				(width 0.1)
				(type default)
			)
			(layer "F.Fab")
		)
		(fp_line
			(start 0.120396 0.2794)
			(end -0.12065 0.2794)
			(stroke
				(width 0.1)
				(type default)
			)
			(layer "F.Fab")
		)
		(fp_line
			(start -0.12065 -0.2794)
			(end 0.12065 -0.2794)
			(stroke
				(width 0.1)
				(type default)
			)
			(layer "F.Fab")
		)
		(fp_line
			(start 0.12065 -0.2794)
			(end 0.12065 -0.3048)
			(stroke
				(width 0.1)
				(type default)
			)
			(layer "F.Fab")
		)
		(fp_line
			(start 0.12065 -0.3048)
			(end 0.67945 -0.3048)
			(stroke
				(width 0.1)
				(type default)
			)
			(layer "F.Fab")
		)
		(fp_line
			(start 0.67945 -0.3048)
			(end 0.67945 0.3048)
			(stroke
				(width 0.1)
				(type default)
			)
			(layer "F.Fab")
		)
		(fp_line
			(start -0.67945 -0.305054)
			(end -0.12065 -0.305054)
			(stroke
				(width 0.1)
				(type default)
			)
			(layer "F.Fab")
		)
		(fp_line
			(start -0.12065 -0.305054)
			(end -0.12065 -0.2794)
			(stroke
				(width 0.1)
				(type default)
			)
			(layer "F.Fab")
		)
		(pad "1" smd circle
			(at -0.40005 0 270)
			(size 0 0)
			(layers "F.Cu" "F.Mask" "F.Paste")
			(net "FM_LED_ACTIVE_E1S_0")
		)
		(pad "2" smd circle
			(at 0.40005 0 270)
			(size 0 0)
			(layers "F.Cu" "F.Mask" "F.Paste")
			(net "FM_LED_ACTIVE_E1S_0_R")
		)
	)
)
